(kicad_pcb
	(version 20241229)
	(generator "pcbnew")
	(generator_version "9.0")
	(general
		(thickness 1.6)
		(legacy_teardrops no)
	)
	(paper "A4")
	(title_block
		(title "GMSL Deserializer")
		(date "2025-10-09")
		(rev "1.0.4")
		(company "Antmicro Ltd")
		(comment 1 "www.antmicro.com")
		(comment 9 "footprints 108-112 of 235")
	)
	(layers
		(0 "F.Cu" signal)
		(4 "In1.Cu" power)
		(6 "In2.Cu" power)
		(2 "B.Cu" signal)
		(9 "F.Adhes" user "F.Adhesive")
		(11 "B.Adhes" user "B.Adhesive")
		(13 "F.Paste" user)
		(15 "B.Paste" user)
		(5 "F.SilkS" user "F.Silkscreen")
		(7 "B.SilkS" user "B.Silkscreen")
		(1 "F.Mask" user)
		(3 "B.Mask" user)
		(17 "Dwgs.User" user "User.Drawings")
		(19 "Cmts.User" user "User.Comments")
		(21 "Eco1.User" user "User.Eco1")
		(23 "Eco2.User" user "User.Eco2")
		(25 "Edge.Cuts" user)
		(27 "Margin" user)
		(31 "F.CrtYd" user "F.Courtyard")
		(29 "B.CrtYd" user "B.Courtyard")
		(35 "F.Fab" user)
		(33 "B.Fab" user)
	)
	(footprint "antmicro-footprints:R_0402_1005Metric"
		(layer "F.Cu")
		(at 130.563 74.422 -90)
		(descr "Resistor SMD 0402")
		(tags "resistor SMD 0402")
		(property "Reference" "R29"
			(at -1.122484 -1.263 90)
			(layer "F.SilkS")
			(effects
				(font
					(size 0.7 0.7)
					(thickness 0.15)
				)
				(justify right bottom)
			)
		)
		(property "Value" "R_13k7_0402"
			(at -1.011843 1.772047 90)
			(layer "F.Fab")
			(effects
				(font
					(size 0.7 0.7)
					(thickness 0.15)
				)
				(justify right bottom)
			)
		)
		(property "Datasheet" "https://www.bourns.com/docs/product-datasheets/cr.pdf"
			(at 0 0 270)
			(layer "F.Fab")
			(hide yes)
			(effects
				(font
					(size 1.27 1.27)
					(thickness 0.15)
				)
			)
		)
		(property "Description" "SMD Chip Resistor, Ceramic, 13.7 kohm, ± 1%, 62.5 mW, 0402 [1005 Metric], Thick Film"
			(at 0 0 270)
			(layer "F.Fab")
			(hide yes)
			(effects
				(font
					(size 1.27 1.27)
					(thickness 0.15)
				)
			)
		)
		(property "Author" "Antmicro"
			(at 56.141 204.985 0)
			(layer "F.Fab")
			(hide yes)
			(effects
				(font
					(size 1 1)
					(thickness 0.15)
				)
			)
		)
		(property "License" "Apache-2.0"
			(at 56.141 204.985 0)
			(layer "F.Fab")
			(hide yes)
			(effects
				(font
					(size 1 1)
					(thickness 0.15)
				)
			)
		)
		(property "MPN" "CR0402-FX-1372GLF"
			(at 56.141 204.985 0)
			(layer "F.Fab")
			(hide yes)
			(effects
				(font
					(size 1 1)
					(thickness 0.15)
				)
			)
		)
		(property "Manufacturer" "Bourns"
			(at 56.141 204.985 0)
			(layer "F.Fab")
			(hide yes)
			(effects
				(font
					(size 1 1)
					(thickness 0.15)
				)
			)
		)
		(property "Tolerance" "1%"
			(at 56.141 204.985 0)
			(layer "F.Fab")
			(hide yes)
			(effects
				(font
					(size 1 1)
					(thickness 0.15)
				)
			)
		)
		(property "Val" "13k7"
			(at 56.141 204.985 0)
			(layer "F.Fab")
			(hide yes)
			(effects
				(font
					(size 1 1)
					(thickness 0.15)
				)
			)
		)
		(sheetname "/Power/")
		(sheetfile "power.kicad_sch")
		(attr smd)
		(fp_rect
			(start -0.925 -0.47)
			(end 0.925 0.47)
			(stroke
				(width 0.05)
				(type default)
			)
			(fill no)
			(layer "F.CrtYd")
		)
		(fp_rect
			(start -0.5 -0.25)
			(end 0.5 0.25)
			(stroke
				(width 0.15)
				(type solid)
			)
			(fill no)
			(layer "F.Fab")
		)
		(pad "1" smd roundrect
			(at -0.48 0 270)
			(size 0.59 0.64)
			(layers "F.Cu" "F.Mask" "F.Paste")
			(roundrect_rratio 0.25)
			(net 1 "GND")
			(pintype "passive")
		)
		(pad "2" smd roundrect
			(at 0.48 0 270)
			(size 0.59 0.64)
			(layers "F.Cu" "F.Mask" "F.Paste")
			(roundrect_rratio 0.25)
			(net 122 "/Power/FB_12V")
			(pintype "passive")
		)
	)
	(footprint "antmicro-footprints:R_0402_1005Metric"
		(layer "F.Cu")
		(at 138.075 95.618)
		(descr "Resistor SMD 0402")
		(tags "resistor SMD 0402")
		(property "Reference" "R35"
			(at 0.99 0.394 0)
			(layer "F.SilkS")
			(effects
				(font
					(size 0.7 0.7)
					(thickness 0.15)
				)
				(justify left bottom)
			)
		)
		(property "Value" "R_12k4_0402"
			(at -1.011843 1.772047 0)
			(layer "F.Fab")
			(effects
				(font
					(size 0.7 0.7)
					(thickness 0.15)
				)
				(justify left bottom)
			)
		)
		(property "Datasheet" "https://www.bourns.com/docs/product-datasheets/cr.pdf"
			(at 0 0 0)
			(layer "F.Fab")
			(hide yes)
			(effects
				(font
					(size 1.27 1.27)
					(thickness 0.15)
				)
			)
		)
		(property "Description" "SMD Chip Resistor, 12.4 kohm, ± 1%, 62.5 mW, 0402 [1005 Metric], Thick Film, General Purpose"
			(at 0 0 0)
			(layer "F.Fab")
			(hide yes)
			(effects
				(font
					(size 1.27 1.27)
					(thickness 0.15)
				)
			)
		)
		(property "Author" "Antmicro"
			(at 0 0 0)
			(layer "F.Fab")
			(hide yes)
			(effects
				(font
					(size 1 1)
					(thickness 0.15)
				)
			)
		)
		(property "License" "Apache-2.0"
			(at 0 0 0)
			(layer "F.Fab")
			(hide yes)
			(effects
				(font
					(size 1 1)
					(thickness 0.15)
				)
			)
		)
		(property "MPN" "CR0402-FX-1242GLF"
			(at 0 0 0)
			(layer "F.Fab")
			(hide yes)
			(effects
				(font
					(size 1 1)
					(thickness 0.15)
				)
			)
		)
		(property "Manufacturer" "Bourns"
			(at 0 0 0)
			(layer "F.Fab")
			(hide yes)
			(effects
				(font
					(size 1 1)
					(thickness 0.15)
				)
			)
		)
		(property "Tolerance" "1%"
			(at 0 0 0)
			(layer "F.Fab")
			(hide yes)
			(effects
				(font
					(size 1 1)
					(thickness 0.15)
				)
			)
		)
		(property "Val" "12k4"
			(at 0 0 0)
			(layer "F.Fab")
			(hide yes)
			(effects
				(font
					(size 1 1)
					(thickness 0.15)
				)
			)
		)
		(sheetname "/Power/")
		(sheetfile "power.kicad_sch")
		(attr smd)
		(fp_rect
			(start -0.925 -0.47)
			(end 0.925 0.47)
			(stroke
				(width 0.05)
				(type default)
			)
			(fill no)
			(layer "F.CrtYd")
		)
		(fp_rect
			(start -0.5 -0.25)
			(end 0.5 0.25)
			(stroke
				(width 0.15)
				(type solid)
			)
			(fill no)
			(layer "F.Fab")
		)
		(pad "1" smd roundrect
			(at -0.48 0)
			(size 0.59 0.64)
			(layers "F.Cu" "F.Mask" "F.Paste")
			(roundrect_rratio 0.25)
			(net 70 "/Power/FB_1V8")
			(pintype "passive")
		)
		(pad "2" smd roundrect
			(at 0.48 0)
			(size 0.59 0.64)
			(layers "F.Cu" "F.Mask" "F.Paste")
			(roundrect_rratio 0.25)
			(net 10 "/Power/OUT_1V8")
			(pintype "passive")
		)
	)
	(footprint "antmicro-footprints:R_0402_1005Metric"
		(layer "F.Cu")
		(at 170.682 68.833)
		(descr "Resistor SMD 0402")
		(tags "resistor SMD 0402")
		(property "Reference" "R66"
			(at 0.768 0.345135 0)
			(layer "F.SilkS")
			(effects
				(font
					(size 0.7 0.7)
					(thickness 0.15)
				)
				(justify left bottom)
			)
		)
		(property "Value" "R_100R_0402"
			(at -1.011843 1.772047 0)
			(layer "F.Fab")
			(effects
				(font
					(size 0.7 0.7)
					(thickness 0.15)
				)
				(justify left bottom)
			)
		)
		(property "Datasheet" "https://www.bourns.com/docs/product-datasheets/cr.pdf"
			(at 0 0 0)
			(layer "F.Fab")
			(hide yes)
			(effects
				(font
					(size 1.27 1.27)
					(thickness 0.15)
				)
			)
		)
		(property "Description" "SMD Chip Resistor, 100 ohm, ± 1%, 62.5 mW, 0402 [1005 Metric], Thick Film, General Purpose"
			(at 0 0 0)
			(layer "F.Fab")
			(hide yes)
			(effects
				(font
					(size 1.27 1.27)
					(thickness 0.15)
				)
			)
		)
		(property "Author" "Antmicro"
			(at 0 0 0)
			(layer "F.Fab")
			(hide yes)
			(effects
				(font
					(size 1 1)
					(thickness 0.15)
				)
			)
		)
		(property "License" "Apache-2.0"
			(at 0 0 0)
			(layer "F.Fab")
			(hide yes)
			(effects
				(font
					(size 1 1)
					(thickness 0.15)
				)
			)
		)
		(property "MPN" "CR0402-FX-1000GLF"
			(at 0 0 0)
			(layer "F.Fab")
			(hide yes)
			(effects
				(font
					(size 1 1)
					(thickness 0.15)
				)
			)
		)
		(property "Manufacturer" "Bourns"
			(at 0 0 0)
			(layer "F.Fab")
			(hide yes)
			(effects
				(font
					(size 1 1)
					(thickness 0.15)
				)
			)
		)
		(property "Tolerance" "1%"
			(at 0 0 0)
			(layer "F.Fab")
			(hide yes)
			(effects
				(font
					(size 1 1)
					(thickness 0.15)
				)
			)
		)
		(property "Val" "100R"
			(at 0 0 0)
			(layer "F.Fab")
			(hide yes)
			(effects
				(font
					(size 1 1)
					(thickness 0.15)
				)
			)
		)
		(sheetname "/Connectors/")
		(sheetfile "connectors.kicad_sch")
		(attr smd)
		(fp_rect
			(start -0.925 -0.47)
			(end 0.925 0.47)
			(stroke
				(width 0.05)
				(type default)
			)
			(fill no)
			(layer "F.CrtYd")
		)
		(fp_rect
			(start -0.5 -0.25)
			(end 0.5 0.25)
			(stroke
				(width 0.15)
				(type solid)
			)
			(fill no)
			(layer "F.Fab")
		)
		(pad "1" smd roundrect
			(at -0.48 0)
			(size 0.59 0.64)
			(layers "F.Cu" "F.Mask" "F.Paste")
			(roundrect_rratio 0.25)
			(net 88 "/Connectors/SDA")
			(pintype "passive")
		)
		(pad "2" smd roundrect
			(at 0.48 0)
			(size 0.59 0.64)
			(layers "F.Cu" "F.Mask" "F.Paste")
			(roundrect_rratio 0.25)
			(net 133 "Net-(U8-A_{1})")
			(pintype "passive")
		)
	)
	(footprint "antmicro-footprints:DFN-10_2.5x1mm"
		(layer "F.Cu")
		(at 150.55 77.555355 -135)
		(property "Reference" "D5"
			(at -0.791817 1.849046 315)
			(unlocked yes)
			(layer "F.SilkS")
			(effects
				(font
					(size 0.7 0.7)
					(thickness 0.15)
				)
				(justify left bottom)
			)
		)
		(property "Value" "PESD4USB5U-TTS"
			(at 2.032 1.524 45)
			(layer "F.Fab")
			(effects
				(font
					(size 0.7 0.7)
					(thickness 0.15)
				)
				(justify right bottom)
			)
		)
		(property "Datasheet" "https://assets.nexperia.com/documents/data-sheet/PESD4USB5U-TTS.pdf"
			(at 0 0 225)
			(layer "F.Fab")
			(hide yes)
			(effects
				(font
					(size 1.27 1.27)
					(thickness 0.15)
				)
			)
		)
		(property "Description" "TVS diode array, 15kV, DFN-10, 5 V, 0.5 pF"
			(at 0 0 225)
			(layer "F.Fab")
			(hide yes)
			(effects
				(font
					(size 1.27 1.27)
					(thickness 0.15)
				)
			)
		)
		(property "Author" "Antmicro"
			(at 202.165008 238.850198 0)
			(layer "F.Fab")
			(hide yes)
			(effects
				(font
					(size 1 1)
					(thickness 0.15)
				)
			)
		)
		(property "License" "Apache-2.0"
			(at 202.165008 238.850198 0)
			(layer "F.Fab")
			(hide yes)
			(effects
				(font
					(size 1 1)
					(thickness 0.15)
				)
			)
		)
		(property "MPN" "PESD4USB5U-TTS"
			(at 202.165008 238.850198 0)
			(layer "F.Fab")
			(hide yes)
			(effects
				(font
					(size 1 1)
					(thickness 0.15)
				)
			)
		)
		(property "Manufacturer" "Nexperia"
			(at 202.165008 238.850198 0)
			(layer "F.Fab")
			(hide yes)
			(effects
				(font
					(size 1 1)
					(thickness 0.15)
				)
			)
		)
		(sheetname "/Deserializer/")
		(sheetfile "deserializer.kicad_sch")
		(attr smd)
		(fp_line
			(start -0.4 1.4)
			(end 0.4 1.4)
			(stroke
				(width 0.15)
				(type solid)
			)
			(layer "F.SilkS")
		)
		(fp_line
			(start 0.4 -1.4)
			(end -0.4 -1.4)
			(stroke
				(width 0.15)
				(type solid)
			)
			(layer "F.SilkS")
		)
		(fp_circle
			(center -0.762 -1.27)
			(end -0.712 -1.270001)
			(stroke
				(width 0.15)
				(type solid)
			)
			(fill yes)
			(layer "F.SilkS")
		)
		(fp_poly
			(pts
				(xy -0.85 -1.6) (xy 0.85 -1.6) (xy 0.85 1.6) (xy -0.85 1.6)
			)
			(stroke
				(width 0.05)
				(type solid)
			)
			(fill no)
			(layer "F.CrtYd")
		)
		(fp_line
			(start 0.5 1.25)
			(end 0.5 -1.25)
			(stroke
				(width 0.15)
				(type solid)
			)
			(layer "F.Fab")
		)
		(fp_line
			(start -0.5 1.25)
			(end 0.5 1.25)
			(stroke
				(width 0.15)
				(type solid)
			)
			(layer "F.Fab")
		)
		(fp_line
			(start 0.5 -1.25)
			(end -0.15 -1.249999)
			(stroke
				(width 0.15)
				(type solid)
			)
			(layer "F.Fab")
		)
		(fp_line
			(start -0.499999 -0.9)
			(end -0.5 1.25)
			(stroke
				(width 0.15)
				(type solid)
			)
			(layer "F.Fab")
		)
		(fp_line
			(start -0.15 -1.249999)
			(end -0.499999 -0.9)
			(stroke
				(width 0.15)
				(type solid)
			)
			(layer "F.Fab")
		)
		(pad "1" smd roundrect
			(at -0.425 -1 135)
			(size 0.2 0.6)
			(layers "F.Cu" "F.Mask" "F.Paste")
			(roundrect_rratio 0.25)
			(net 16 "/Deserializer/SIOD_P")
			(pinfunction "1")
			(pintype "passive")
			(solder_mask_margin 0.05)
		)
		(pad "2" smd roundrect
			(at -0.425 -0.5 135)
			(size 0.2 0.6)
			(layers "F.Cu" "F.Mask" "F.Paste")
			(roundrect_rratio 0.25)
			(net 24 "/Deserializer/SIOD_N")
			(pinfunction "2")
			(pintype "passive")
			(solder_mask_margin 0.05)
		)
		(pad "3" smd roundrect
			(at -0.424999 0 135)
			(size 0.4 0.6)
			(layers "F.Cu" "F.Mask" "F.Paste")
			(roundrect_rratio 0.25)
			(net 1 "GND")
			(pinfunction "3")
			(pintype "passive")
			(solder_mask_margin 0.05)
		)
		(pad "4" smd roundrect
			(at -0.425 0.5 135)
			(size 0.2 0.6)
			(layers "F.Cu" "F.Mask" "F.Paste")
			(roundrect_rratio 0.25)
			(net 22 "/Deserializer/SIOC_N")
			(pinfunction "4")
			(pintype "passive")
			(solder_mask_margin 0.05)
		)
		(pad "5" smd roundrect
			(at -0.425 1 135)
			(size 0.2 0.6)
			(layers "F.Cu" "F.Mask" "F.Paste")
			(roundrect_rratio 0.25)
			(net 15 "/Deserializer/SIOC_P")
			(pinfunction "5")
			(pintype "passive")
			(solder_mask_margin 0.05)
		)
		(pad "6" smd roundrect
			(at 0.425 1 135)
			(size 0.2 0.6)
			(layers "F.Cu" "F.Mask" "F.Paste")
			(roundrect_rratio 0.25)
			(net 15 "/Deserializer/SIOC_P")
			(pinfunction "6")
			(pintype "passive")
			(solder_mask_margin 0.05)
		)
		(pad "7" smd roundrect
			(at 0.425 0.5 135)
			(size 0.2 0.6)
			(layers "F.Cu" "F.Mask" "F.Paste")
			(roundrect_rratio 0.25)
			(net 22 "/Deserializer/SIOC_N")
			(pinfunction "7")
			(pintype "passive")
			(solder_mask_margin 0.05)
		)
		(pad "8" smd roundrect
			(at 0.424999 0 135)
			(size 0.4 0.6)
			(layers "F.Cu" "F.Mask" "F.Paste")
			(roundrect_rratio 0.25)
			(net 1 "GND")
			(pinfunction "8")
			(pintype "passive")
			(solder_mask_margin 0.05)
		)
		(pad "9" smd roundrect
			(at 0.425 -0.5 135)
			(size 0.2 0.6)
			(layers "F.Cu" "F.Mask" "F.Paste")
			(roundrect_rratio 0.25)
			(net 24 "/Deserializer/SIOD_N")
			(pinfunction "9")
			(pintype "passive")
			(solder_mask_margin 0.05)
		)
		(pad "10" smd roundrect
			(at 0.425 -1 135)
			(size 0.2 0.6)
			(layers "F.Cu" "F.Mask" "F.Paste")
			(roundrect_rratio 0.25)
			(net 16 "/Deserializer/SIOD_P")
			(pinfunction "10")
			(pintype "passive")
			(solder_mask_margin 0.05)
		)
	)
	(footprint "antmicro-footprints:C_0402_1005Metric"
		(layer "F.Cu")
		(at 158.424 66.548 90)
		(descr "Capacitor SMD 0402")
		(tags "capacitor SMD 0402")
		(property "Reference" "C13"
			(at -1.905 1.215 90)
			(layer "F.SilkS")
			(effects
				(font
					(size 0.7 0.7)
					(thickness 0.15)
				)
				(justify left bottom)
			)
		)
		(property "Value" "C_10n_0402"
			(at -1.022927 2.155213 90)
			(layer "F.Fab")
			(effects
				(font
					(size 0.7 0.7)
					(thickness 0.15)
				)
				(justify left bottom)
			)
		)
		(property "Datasheet" "https://www.murata.com/products/productdetail?partno=GRM155R71H103KA88%23"
			(at 0 0 90)
			(layer "F.Fab")
			(hide yes)
			(effects
				(font
					(size 1.27 1.27)
					(thickness 0.15)
				)
			)
		)
		(property "Description" "SMD Multilayer Ceramic Capacitor, 10000 pF, 50 V, 0402 [1005 Metric], ± 10%, X7R, GRM Series"
			(at 0 0 90)
			(layer "F.Fab")
			(hide yes)
			(effects
				(font
					(size 1.27 1.27)
					(thickness 0.15)
				)
			)
		)
		(property "Author" "Antmicro"
			(at 224.972 -91.876 0)
			(layer "F.Fab")
			(hide yes)
			(effects
				(font
					(size 1 1)
					(thickness 0.15)
				)
			)
		)
		(property "Dielectric" "X7R"
			(at 224.972 -91.876 0)
			(layer "F.Fab")
			(hide yes)
			(effects
				(font
					(size 1 1)
					(thickness 0.15)
				)
			)
		)
		(property "License" "Apache-2.0"
			(at 224.972 -91.876 0)
			(layer "F.Fab")
			(hide yes)
			(effects
				(font
					(size 1 1)
					(thickness 0.15)
				)
			)
		)
		(property "MPN" "GRM155R71H103KA88D"
			(at 224.972 -91.876 0)
			(layer "F.Fab")
			(hide yes)
			(effects
				(font
					(size 1 1)
					(thickness 0.15)
				)
			)
		)
		(property "Manufacturer" "Murata"
			(at 224.972 -91.876 0)
			(layer "F.Fab")
			(hide yes)
			(effects
				(font
					(size 1 1)
					(thickness 0.15)
				)
			)
		)
		(property "Val" "10n"
			(at 224.972 -91.876 0)
			(layer "F.Fab")
			(hide yes)
			(effects
				(font
					(size 1 1)
					(thickness 0.15)
				)
			)
		)
		(property "Voltage" "50V"
			(at 224.972 -91.876 0)
			(layer "F.Fab")
			(hide yes)
			(effects
				(font
					(size 1 1)
					(thickness 0.15)
				)
			)
		)
		(sheetname "/Power/")
		(sheetfile "power.kicad_sch")
		(attr smd)
		(fp_rect
			(start -0.925 -0.47)
			(end 0.925 0.47)
			(stroke
				(width 0.05)
				(type default)
			)
			(fill no)
			(layer "F.CrtYd")
		)
		(fp_line
			(start 0.504 -0.25)
			(end 0.504 0.248)
			(stroke
				(width 0.15)
				(type solid)
			)
			(layer "F.Fab")
		)
		(fp_line
			(start -0.494 -0.25)
			(end 0.504 -0.25)
			(stroke
				(width 0.15)
				(type solid)
			)
			(layer "F.Fab")
		)
		(fp_line
			(start 0.504 0.248)
			(end -0.494 0.248)
			(stroke
				(width 0.15)
				(type solid)
			)
			(layer "F.Fab")
		)
		(fp_line
			(start -0.494 0.248)
			(end -0.494 -0.25)
			(stroke
				(width 0.15)
				(type solid)
			)
			(layer "F.Fab")
		)
		(pad "1" smd roundrect
			(at -0.48 0 90)
			(size 0.59 0.64)
			(layers "F.Cu" "F.Mask" "F.Paste")
			(roundrect_rratio 0.25)
			(net 1 "GND")
			(pintype "passive")
		)
		(pad "2" smd roundrect
			(at 0.48 0 90)
			(size 0.59 0.64)
			(layers "F.Cu" "F.Mask" "F.Paste")
			(roundrect_rratio 0.25)
			(net 4 "+12V")
			(pintype "passive")
		)
	)
)
